(kicad_pcb
	(version 20260206)
	(generator "pcbnew")
	(generator_version "10.0")
	(general
		(thickness 1.6)
		(legacy_teardrops no)
	)
	(paper "A4")
	(title_block
		(title "01162023_DA0F0TEBIF0_F0T_Expander_BD_F_brd_V02_OCP.brd")
		(comment 1 "Grand Teton / footprints 4001-4008 of 9728")
	)
	(layers
		(0 "F.Cu" signal "TOP")
		(4 "In1.Cu" signal "GND")
		(6 "In2.Cu" signal "VCC")
		(8 "In3.Cu" signal "VCC1")
		(10 "In4.Cu" signal "GND1")
		(12 "In5.Cu" signal "IN1")
		(14 "In6.Cu" signal "GND2")
		(16 "In7.Cu" signal "IN2")
		(18 "In8.Cu" signal "GND3")
		(20 "In9.Cu" signal "IN3")
		(22 "In10.Cu" signal "GND4")
		(24 "In11.Cu" signal "IN4")
		(26 "In12.Cu" signal "GND5")
		(28 "In13.Cu" signal "IN5")
		(30 "In14.Cu" signal "GND6")
		(32 "In15.Cu" signal "IN6")
		(34 "In16.Cu" signal "GND7")
		(2 "B.Cu" signal "BOTTOM")
		(9 "F.Adhes" user "F.Adhesive")
		(11 "B.Adhes" user "B.Adhesive")
		(13 "F.Paste" user "Package Geometry/Pastemask Top")
		(15 "B.Paste" user "Package Geometry/Pastemask Bottom")
		(5 "F.SilkS" user "Ref Des/Silkscreen Top")
		(7 "B.SilkS" user "Ref Des/Silkscreen Bottom")
		(1 "F.Mask" user "Board Geometry/Soldermask Top")
		(3 "B.Mask" user "Board Geometry/Soldermask Bottom")
		(17 "Dwgs.User" user "User.Drawings")
		(19 "Cmts.User" user "User.Comments")
		(21 "Eco1.User" user "User.Eco1")
		(23 "Eco2.User" user "User.Eco2")
		(25 "Edge.Cuts" user "Board Geometry/Outline")
		(27 "Margin" user)
		(31 "F.CrtYd" user "Package Geometry/Place Bound Top")
		(29 "B.CrtYd" user "Package Geometry/Place Bound Bottom")
		(35 "F.Fab" user "Ref Des/Assembly Top")
		(33 "B.Fab" user "Ref Des/Assembly Bottom")
	)
	(footprint ""
		(layer "F.Cu")
		(at 378.453396 -288.190432)
		(property "Reference" "L142"
			(at 0 0 0)
			(layer "F.SilkS")
			(hide yes)
			(effects
				(font
					(size 1.27 1.27)
				)
			)
		)
		(property "Value" ""
			(at 0 0 0)
			(layer "F.Fab")
			(effects
				(font
					(size 1.27 1.27)
				)
			)
		)
		(duplicate_pad_numbers_are_jumpers no)
		(fp_line
			(start -1.63576 -0.8128)
			(end -1.63576 0.8128)
			(stroke
				(width 0.1524)
				(type default)
			)
			(layer "F.SilkS")
		)
		(fp_line
			(start -1.63576 -0.8128)
			(end 1.63576 -0.8128)
			(stroke
				(width 0.1524)
				(type default)
			)
			(layer "F.SilkS")
		)
		(fp_line
			(start 1.63576 -0.8128)
			(end 1.63576 0.8128)
			(stroke
				(width 0.1524)
				(type default)
			)
			(layer "F.SilkS")
		)
		(fp_line
			(start 1.63576 0.8128)
			(end -1.63576 0.8128)
			(stroke
				(width 0.1524)
				(type default)
			)
			(layer "F.SilkS")
		)
		(fp_line
			(start -1.56083 -0.738632)
			(end -1.56083 0.7366)
			(stroke
				(width 0.1)
				(type default)
			)
			(layer "F.Fab")
		)
		(fp_line
			(start -1.56083 0.7366)
			(end -1.524 0.7366)
			(stroke
				(width 0.1)
				(type default)
			)
			(layer "F.Fab")
		)
		(fp_line
			(start -1.524 0.7366)
			(end 1.524 0.7366)
			(stroke
				(width 0.1)
				(type default)
			)
			(layer "F.Fab")
		)
		(fp_line
			(start 1.524 0.7366)
			(end 1.560576 0.7366)
			(stroke
				(width 0.1)
				(type default)
			)
			(layer "F.Fab")
		)
		(fp_line
			(start 1.560576 -0.738632)
			(end -1.56083 -0.738632)
			(stroke
				(width 0.1)
				(type default)
			)
			(layer "F.Fab")
		)
		(fp_line
			(start 1.560576 0.7366)
			(end 1.560576 -0.738632)
			(stroke
				(width 0.1)
				(type default)
			)
			(layer "F.Fab")
		)
		(pad "1" smd rect
			(at -0.94996 0 180)
			(size 1.1176 1.3716)
			(layers "F.Cu" "F.Mask" "F.Paste")
			(net "P1V8_PLL0_PEX3")
		)
		(pad "2" smd rect
			(at 0.94996 0 180)
			(size 1.1176 1.3716)
			(layers "F.Cu" "F.Mask" "F.Paste")
			(net "PCEPLL6_VDDA18_PEX3")
		)
	)
	(footprint ""
		(layer "F.Cu")
		(at 379.956314 -61.487812 180)
		(property "Reference" "R6013"
			(at 0 0 180)
			(layer "F.SilkS")
			(hide yes)
			(effects
				(font
					(size 1.27 1.27)
				)
			)
		)
		(property "Value" ""
			(at 0 0 180)
			(layer "F.Fab")
			(effects
				(font
					(size 1.27 1.27)
				)
			)
		)
		(duplicate_pad_numbers_are_jumpers no)
		(fp_line
			(start 0.7874 0.4064)
			(end -0.7874 0.4064)
			(stroke
				(width 0.1524)
				(type default)
			)
			(layer "F.SilkS")
		)
		(fp_line
			(start 0.7874 -0.4064)
			(end 0.7874 0.4064)
			(stroke
				(width 0.1524)
				(type default)
			)
			(layer "F.SilkS")
		)
		(fp_line
			(start -0.7874 0.4064)
			(end -0.7874 -0.4064)
			(stroke
				(width 0.1524)
				(type default)
			)
			(layer "F.SilkS")
		)
		(fp_line
			(start -0.7874 -0.4064)
			(end 0.7874 -0.4064)
			(stroke
				(width 0.1524)
				(type default)
			)
			(layer "F.SilkS")
		)
		(fp_line
			(start 0.67945 0.3048)
			(end 0.120396 0.3048)
			(stroke
				(width 0.1)
				(type default)
			)
			(layer "F.Fab")
		)
		(fp_line
			(start 0.67945 -0.3048)
			(end 0.67945 0.3048)
			(stroke
				(width 0.1)
				(type default)
			)
			(layer "F.Fab")
		)
		(fp_line
			(start 0.12065 -0.2794)
			(end 0.12065 -0.3048)
			(stroke
				(width 0.1)
				(type default)
			)
			(layer "F.Fab")
		)
		(fp_line
			(start 0.12065 -0.3048)
			(end 0.67945 -0.3048)
			(stroke
				(width 0.1)
				(type default)
			)
			(layer "F.Fab")
		)
		(fp_line
			(start 0.120396 0.3048)
			(end 0.120396 0.2794)
			(stroke
				(width 0.1)
				(type default)
			)
			(layer "F.Fab")
		)
		(fp_line
			(start 0.120396 0.2794)
			(end -0.12065 0.2794)
			(stroke
				(width 0.1)
				(type default)
			)
			(layer "F.Fab")
		)
		(fp_line
			(start -0.12065 0.3048)
			(end -0.67945 0.3048)
			(stroke
				(width 0.1)
				(type default)
			)
			(layer "F.Fab")
		)
		(fp_line
			(start -0.12065 0.2794)
			(end -0.12065 0.3048)
			(stroke
				(width 0.1)
				(type default)
			)
			(layer "F.Fab")
		)
		(fp_line
			(start -0.12065 -0.2794)
			(end 0.12065 -0.2794)
			(stroke
				(width 0.1)
				(type default)
			)
			(layer "F.Fab")
		)
		(fp_line
			(start -0.12065 -0.305054)
			(end -0.12065 -0.2794)
			(stroke
				(width 0.1)
				(type default)
			)
			(layer "F.Fab")
		)
		(fp_line
			(start -0.67945 0.3048)
			(end -0.67945 -0.305054)
			(stroke
				(width 0.1)
				(type default)
			)
			(layer "F.Fab")
		)
		(fp_line
			(start -0.67945 -0.305054)
			(end -0.12065 -0.305054)
			(stroke
				(width 0.1)
				(type default)
			)
			(layer "F.Fab")
		)
		(pad "1" smd circle
			(at -0.40005 0 180)
			(size 0 0)
			(layers "F.Cu" "F.Mask" "F.Paste")
			(net "P3V3_AUX")
		)
		(pad "2" smd circle
			(at 0.40005 0 180)
			(size 0 0)
			(layers "F.Cu" "F.Mask" "F.Paste")
			(net "PWRGD_P12V_SSD13_D")
		)
	)
	(footprint ""
		(layer "F.Cu")
		(at 422.619932 -356.244906 90)
		(property "Reference" "C813"
			(at 0 0 90)
			(layer "F.SilkS")
			(hide yes)
			(effects
				(font
					(size 1.27 1.27)
				)
			)
		)
		(property "Value" ""
			(at 0 0 90)
			(layer "F.Fab")
			(effects
				(font
					(size 1.27 1.27)
				)
			)
		)
		(duplicate_pad_numbers_are_jumpers no)
		(fp_line
			(start 0.299974 -0.150114)
			(end 0.299974 0.150114)
			(stroke
				(width 0.1)
				(type default)
			)
			(layer "F.Fab")
		)
		(fp_line
			(start -0.299974 -0.150114)
			(end 0.299974 -0.150114)
			(stroke
				(width 0.1)
				(type default)
			)
			(layer "F.Fab")
		)
		(fp_line
			(start 0.299974 0.150114)
			(end -0.299974 0.150114)
			(stroke
				(width 0.1)
				(type default)
			)
			(layer "F.Fab")
		)
		(fp_line
			(start -0.299974 0.150114)
			(end -0.299974 -0.150114)
			(stroke
				(width 0.1)
				(type default)
			)
			(layer "F.Fab")
		)
		(pad "1" smd rect
			(at -0.2667 0 90)
			(size 0.3048 0.381)
			(layers "F.Cu" "F.Mask" "F.Paste")
			(net "P5E_PEX3_STN7_TX_DN<118>")
		)
		(pad "2" smd rect
			(at 0.2667 0 90)
			(size 0.3048 0.381)
			(layers "F.Cu" "F.Mask" "F.Paste")
			(net "P5E_PEX3_STN7_TX_C_DN<118>")
		)
	)
	(footprint ""
		(layer "F.Cu")
		(at 26.930096 -294.005508 -90)
		(property "Reference" "C3035"
			(at 0 0 270)
			(layer "F.SilkS")
			(hide yes)
			(effects
				(font
					(size 1.27 1.27)
				)
			)
		)
		(property "Value" ""
			(at 0 0 270)
			(layer "F.Fab")
			(effects
				(font
					(size 1.27 1.27)
				)
			)
		)
		(duplicate_pad_numbers_are_jumpers no)
		(fp_line
			(start -1.2954 0.5842)
			(end -1.2954 -0.5842)
			(stroke
				(width 0.1524)
				(type default)
			)
			(layer "F.SilkS")
		)
		(fp_line
			(start 1.2954 0.5842)
			(end -1.2954 0.5842)
			(stroke
				(width 0.1524)
				(type default)
			)
			(layer "F.SilkS")
		)
		(fp_line
			(start -1.2954 -0.5842)
			(end 1.2954 -0.5842)
			(stroke
				(width 0.1524)
				(type default)
			)
			(layer "F.SilkS")
		)
		(fp_line
			(start 1.2954 -0.5842)
			(end 1.2954 0.5842)
			(stroke
				(width 0.1524)
				(type default)
			)
			(layer "F.SilkS")
		)
		(fp_line
			(start -0.8636 0.4572)
			(end -0.8636 0.4064)
			(stroke
				(width 0.1)
				(type default)
			)
			(layer "F.Fab")
		)
		(fp_line
			(start 0.8636 0.4572)
			(end -0.8636 0.4572)
			(stroke
				(width 0.1)
				(type default)
			)
			(layer "F.Fab")
		)
		(fp_line
			(start -1.1938 0.4064)
			(end -1.1938 -0.4064)
			(stroke
				(width 0.1)
				(type default)
			)
			(layer "F.Fab")
		)
		(fp_line
			(start -0.8636 0.4064)
			(end -1.1938 0.4064)
			(stroke
				(width 0.1)
				(type default)
			)
			(layer "F.Fab")
		)
		(fp_line
			(start 0.8636 0.4064)
			(end 0.8636 0.4572)
			(stroke
				(width 0.1)
				(type default)
			)
			(layer "F.Fab")
		)
		(fp_line
			(start 1.1938 0.4064)
			(end 0.8636 0.4064)
			(stroke
				(width 0.1)
				(type default)
			)
			(layer "F.Fab")
		)
		(fp_line
			(start -1.1938 -0.4064)
			(end -0.8636 -0.4064)
			(stroke
				(width 0.1)
				(type default)
			)
			(layer "F.Fab")
		)
		(fp_line
			(start -0.8636 -0.4064)
			(end -0.8636 -0.4572)
			(stroke
				(width 0.1)
				(type default)
			)
			(layer "F.Fab")
		)
		(fp_line
			(start 0.8636 -0.4064)
			(end 1.1938 -0.4064)
			(stroke
				(width 0.1)
				(type default)
			)
			(layer "F.Fab")
		)
		(fp_line
			(start 1.1938 -0.4064)
			(end 1.1938 0.4064)
			(stroke
				(width 0.1)
				(type default)
			)
			(layer "F.Fab")
		)
		(fp_line
			(start -0.8636 -0.4572)
			(end 0.8636 -0.4572)
			(stroke
				(width 0.1)
				(type default)
			)
			(layer "F.Fab")
		)
		(fp_line
			(start 0.8636 -0.4572)
			(end 0.8636 -0.4064)
			(stroke
				(width 0.1)
				(type default)
			)
			(layer "F.Fab")
		)
		(pad "1" smd rect
			(at -0.7366 0 180)
			(size 0.7112 0.8128)
			(layers "F.Cu" "F.Mask" "F.Paste")
			(net "P1V8_PLL0_PEX0")
		)
		(pad "2" smd rect
			(at 0.7366 0 180)
			(size 0.7112 0.8128)
			(layers "F.Cu" "F.Mask" "F.Paste")
			(net "GND")
		)
	)
	(footprint ""
		(layer "F.Cu")
		(at 131.435856 -170.599862 90)
		(property "Reference" "R1092"
			(at 0 0 90)
			(layer "F.SilkS")
			(hide yes)
			(effects
				(font
					(size 1.27 1.27)
				)
			)
		)
		(property "Value" ""
			(at 0 0 90)
			(layer "F.Fab")
			(effects
				(font
					(size 1.27 1.27)
				)
			)
		)
		(duplicate_pad_numbers_are_jumpers no)
		(fp_line
			(start 0.7874 0.4064)
			(end -0.7874 0.4064)
			(stroke
				(width 0.1524)
				(type default)
			)
			(layer "F.SilkS")
		)
		(fp_line
			(start -0.12065 -0.305054)
			(end -0.12065 -0.2794)
			(stroke
				(width 0.1)
				(type default)
			)
			(layer "F.Fab")
		)
		(fp_line
			(start -0.67945 -0.305054)
			(end -0.12065 -0.305054)
			(stroke
				(width 0.1)
				(type default)
			)
			(layer "F.Fab")
		)
		(fp_line
			(start 0.67945 -0.3048)
			(end 0.67945 0.3048)
			(stroke
				(width 0.1)
				(type default)
			)
			(layer "F.Fab")
		)
		(fp_line
			(start 0.12065 -0.3048)
			(end 0.67945 -0.3048)
			(stroke
				(width 0.1)
				(type default)
			)
			(layer "F.Fab")
		)
		(fp_line
			(start 0.12065 -0.2794)
			(end 0.12065 -0.3048)
			(stroke
				(width 0.1)
				(type default)
			)
			(layer "F.Fab")
		)
		(fp_line
			(start -0.12065 -0.2794)
			(end 0.12065 -0.2794)
			(stroke
				(width 0.1)
				(type default)
			)
			(layer "F.Fab")
		)
		(fp_line
			(start 0.120396 0.2794)
			(end -0.12065 0.2794)
			(stroke
				(width 0.1)
				(type default)
			)
			(layer "F.Fab")
		)
		(fp_line
			(start -0.12065 0.2794)
			(end -0.12065 0.3048)
			(stroke
				(width 0.1)
				(type default)
			)
			(layer "F.Fab")
		)
		(fp_line
			(start 0.67945 0.3048)
			(end 0.120396 0.3048)
			(stroke
				(width 0.1)
				(type default)
			)
			(layer "F.Fab")
		)
		(fp_line
			(start 0.120396 0.3048)
			(end 0.120396 0.2794)
			(stroke
				(width 0.1)
				(type default)
			)
			(layer "F.Fab")
		)
		(fp_line
			(start -0.12065 0.3048)
			(end -0.67945 0.3048)
			(stroke
				(width 0.1)
				(type default)
			)
			(layer "F.Fab")
		)
		(fp_line
			(start -0.67945 0.3048)
			(end -0.67945 -0.305054)
			(stroke
				(width 0.1)
				(type default)
			)
			(layer "F.Fab")
		)
		(pad "1" smd circle
			(at -0.40005 0 90)
			(size 0 0)
			(layers "F.Cu" "F.Mask" "F.Paste")
			(net "CLK_100M_DB2000QL_PEX3_S1_R_DN")
		)
		(pad "2" smd circle
			(at 0.40005 0 90)
			(size 0 0)
			(layers "F.Cu" "F.Mask" "F.Paste")
			(net "CLK_100M_DB2000QL_PEX3_S1_DN")
		)
	)
	(footprint ""
		(layer "F.Cu")
		(at 170.441874 -27.006296 -90)
		(property "Reference" "PR7112"
			(at 0 0 270)
			(layer "F.SilkS")
			(hide yes)
			(effects
				(font
					(size 1.27 1.27)
				)
			)
		)
		(property "Value" ""
			(at 0 0 270)
			(layer "F.Fab")
			(effects
				(font
					(size 1.27 1.27)
				)
			)
		)
		(duplicate_pad_numbers_are_jumpers no)
		(fp_line
			(start -0.7874 0.4064)
			(end -0.7874 -0.4064)
			(stroke
				(width 0.1524)
				(type default)
			)
			(layer "F.SilkS")
		)
		(fp_line
			(start 0.7874 0.4064)
			(end -0.7874 0.4064)
			(stroke
				(width 0.1524)
				(type default)
			)
			(layer "F.SilkS")
		)
		(fp_line
			(start -0.7874 -0.4064)
			(end 0.7874 -0.4064)
			(stroke
				(width 0.1524)
				(type default)
			)
			(layer "F.SilkS")
		)
		(fp_line
			(start 0.7874 -0.4064)
			(end 0.7874 0.4064)
			(stroke
				(width 0.1524)
				(type default)
			)
			(layer "F.SilkS")
		)
		(fp_line
			(start -0.67945 0.3048)
			(end -0.67945 -0.305054)
			(stroke
				(width 0.1)
				(type default)
			)
			(layer "F.Fab")
		)
		(fp_line
			(start -0.12065 0.3048)
			(end -0.67945 0.3048)
			(stroke
				(width 0.1)
				(type default)
			)
			(layer "F.Fab")
		)
		(fp_line
			(start 0.120396 0.3048)
			(end 0.120396 0.2794)
			(stroke
				(width 0.1)
				(type default)
			)
			(layer "F.Fab")
		)
		(fp_line
			(start 0.67945 0.3048)
			(end 0.120396 0.3048)
			(stroke
				(width 0.1)
				(type default)
			)
			(layer "F.Fab")
		)
		(fp_line
			(start -0.12065 0.2794)
			(end -0.12065 0.3048)
			(stroke
				(width 0.1)
				(type default)
			)
			(layer "F.Fab")
		)
		(fp_line
			(start 0.120396 0.2794)
			(end -0.12065 0.2794)
			(stroke
				(width 0.1)
				(type default)
			)
			(layer "F.Fab")
		)
		(fp_line
			(start -0.12065 -0.2794)
			(end 0.12065 -0.2794)
			(stroke
				(width 0.1)
				(type default)
			)
			(layer "F.Fab")
		)
		(fp_line
			(start 0.12065 -0.2794)
			(end 0.12065 -0.3048)
			(stroke
				(width 0.1)
				(type default)
			)
			(layer "F.Fab")
		)
		(fp_line
			(start 0.12065 -0.3048)
			(end 0.67945 -0.3048)
			(stroke
				(width 0.1)
				(type default)
			)
			(layer "F.Fab")
		)
		(fp_line
			(start 0.67945 -0.3048)
			(end 0.67945 0.3048)
			(stroke
				(width 0.1)
				(type default)
			)
			(layer "F.Fab")
		)
		(fp_line
			(start -0.67945 -0.305054)
			(end -0.12065 -0.305054)
			(stroke
				(width 0.1)
				(type default)
			)
			(layer "F.Fab")
		)
		(fp_line
			(start -0.12065 -0.305054)
			(end -0.12065 -0.2794)
			(stroke
				(width 0.1)
				(type default)
			)
			(layer "F.Fab")
		)
		(pad "1" smd circle
			(at -0.40005 0 270)
			(size 0 0)
			(layers "F.Cu" "F.Mask" "F.Paste")
			(net "P3V3_SSD6_CO_ILIMIT")
		)
		(pad "2" smd circle
			(at 0.40005 0 270)
			(size 0 0)
			(layers "F.Cu" "F.Mask" "F.Paste")
			(net "GND")
		)
	)
	(footprint ""
		(layer "F.Cu")
		(at 127.29972 -166.407846)
		(property "Reference" "R6669"
			(at 0 0 0)
			(layer "F.SilkS")
			(hide yes)
			(effects
				(font
					(size 1.27 1.27)
				)
			)
		)
		(property "Value" ""
			(at 0 0 0)
			(layer "F.Fab")
			(effects
				(font
					(size 1.27 1.27)
				)
			)
		)
		(duplicate_pad_numbers_are_jumpers no)
		(fp_line
			(start -0.7874 -0.4064)
			(end 0.7874 -0.4064)
			(stroke
				(width 0.1524)
				(type default)
			)
			(layer "F.SilkS")
		)
		(fp_line
			(start -0.7874 0.4064)
			(end -0.7874 -0.4064)
			(stroke
				(width 0.1524)
				(type default)
			)
			(layer "F.SilkS")
		)
		(fp_line
			(start 0.7874 -0.4064)
			(end 0.7874 0.4064)
			(stroke
				(width 0.1524)
				(type default)
			)
			(layer "F.SilkS")
		)
		(fp_line
			(start 0.7874 0.4064)
			(end -0.7874 0.4064)
			(stroke
				(width 0.1524)
				(type default)
			)
			(layer "F.SilkS")
		)
		(fp_line
			(start -0.67945 -0.305054)
			(end -0.12065 -0.305054)
			(stroke
				(width 0.1)
				(type default)
			)
			(layer "F.Fab")
		)
		(fp_line
			(start -0.67945 0.3048)
			(end -0.67945 -0.305054)
			(stroke
				(width 0.1)
				(type default)
			)
			(layer "F.Fab")
		)
		(fp_line
			(start -0.12065 -0.305054)
			(end -0.12065 -0.2794)
			(stroke
				(width 0.1)
				(type default)
			)
			(layer "F.Fab")
		)
		(fp_line
			(start -0.12065 -0.2794)
			(end 0.12065 -0.2794)
			(stroke
				(width 0.1)
				(type default)
			)
			(layer "F.Fab")
		)
		(fp_line
			(start -0.12065 0.2794)
			(end -0.12065 0.3048)
			(stroke
				(width 0.1)
				(type default)
			)
			(layer "F.Fab")
		)
		(fp_line
			(start -0.12065 0.3048)
			(end -0.67945 0.3048)
			(stroke
				(width 0.1)
				(type default)
			)
			(layer "F.Fab")
		)
		(fp_line
			(start 0.120396 0.2794)
			(end -0.12065 0.2794)
			(stroke
				(width 0.1)
				(type default)
			)
			(layer "F.Fab")
		)
		(fp_line
			(start 0.120396 0.3048)
			(end 0.120396 0.2794)
			(stroke
				(width 0.1)
				(type default)
			)
			(layer "F.Fab")
		)
		(fp_line
			(start 0.12065 -0.3048)
			(end 0.67945 -0.3048)
			(stroke
				(width 0.1)
				(type default)
			)
			(layer "F.Fab")
		)
		(fp_line
			(start 0.12065 -0.2794)
			(end 0.12065 -0.3048)
			(stroke
				(width 0.1)
				(type default)
			)
			(layer "F.Fab")
		)
		(fp_line
			(start 0.67945 -0.3048)
			(end 0.67945 0.3048)
			(stroke
				(width 0.1)
				(type default)
			)
			(layer "F.Fab")
		)
		(fp_line
			(start 0.67945 0.3048)
			(end 0.120396 0.3048)
			(stroke
				(width 0.1)
				(type default)
			)
			(layer "F.Fab")
		)
		(pad "1" smd circle
			(at -0.40005 0)
			(size 0 0)
			(layers "F.Cu" "F.Mask" "F.Paste")
			(net "NIC0_CLK_EN_BUF_R_N")
		)
		(pad "2" smd circle
			(at 0.40005 0)
			(size 0 0)
			(layers "F.Cu" "F.Mask" "F.Paste")
			(net "P3V3")
		)
	)
	(footprint ""
		(layer "F.Cu")
		(at 198.76135 -131.686808 180)
		(property "Reference" "C233"
			(at 0 0 180)
			(layer "F.SilkS")
			(hide yes)
			(effects
				(font
					(size 1.27 1.27)
				)
			)
		)
		(property "Value" ""
			(at 0 0 180)
			(layer "F.Fab")
			(effects
				(font
					(size 1.27 1.27)
				)
			)
		)
		(duplicate_pad_numbers_are_jumpers no)
		(fp_line
			(start 0.299974 0.150114)
			(end -0.299974 0.150114)
			(stroke
				(width 0.1)
				(type default)
			)
			(layer "F.Fab")
		)
		(fp_line
			(start 0.299974 -0.150114)
			(end 0.299974 0.150114)
			(stroke
				(width 0.1)
				(type default)
			)
			(layer "F.Fab")
		)
		(fp_line
			(start -0.299974 0.150114)
			(end -0.299974 -0.150114)
			(stroke
				(width 0.1)
				(type default)
			)
			(layer "F.Fab")
		)
		(fp_line
			(start -0.299974 -0.150114)
			(end 0.299974 -0.150114)
			(stroke
				(width 0.1)
				(type default)
			)
			(layer "F.Fab")
		)
		(pad "1" smd rect
			(at -0.2667 0 180)
			(size 0.3048 0.381)
			(layers "F.Cu" "F.Mask" "F.Paste")
			(net "P5E_PEX1_STN0_TX_DN<5>")
		)
		(pad "2" smd rect
			(at 0.2667 0 180)
			(size 0.3048 0.381)
			(layers "F.Cu" "F.Mask" "F.Paste")
			(net "P5E_PEX1_STN0_TX_C_DN<5>")
		)
	)
)
